(kicad_pcb
	(version 20221018)
	(generator pcbnew)
	(general
    (thickness 1.62)
  )
	(paper "A4")
	(title_block
    (title "ECP5 - Datacenter Secure Control Module (DC-SCM)")
    (date "2024-07-01")
    (rev "1.2.1")
		(comment 9 "footprints 51-55 of 506")
	)
	(layers
    (0 "F.Cu" signal)
    (1 "In1.Cu" power)
    (2 "In2.Cu" signal)
    (3 "In3.Cu" power)
    (4 "In4.Cu" power)
    (5 "In5.Cu" signal)
    (6 "In6.Cu" power)
    (31 "B.Cu" signal)
    (32 "B.Adhes" user "B.Adhesive")
    (33 "F.Adhes" user "F.Adhesive")
    (34 "B.Paste" user)
    (35 "F.Paste" user)
    (36 "B.SilkS" user "B.Silkscreen")
    (37 "F.SilkS" user "F.Silkscreen")
    (38 "B.Mask" user)
    (39 "F.Mask" user)
    (40 "Dwgs.User" user "User.Drawings")
    (41 "Cmts.User" user "User.Comments")
    (42 "Eco1.User" user "User.Eco1")
    (43 "Eco2.User" user "User.Eco2")
    (44 "Edge.Cuts" user)
    (45 "Margin" user)
    (46 "B.CrtYd" user "B.Courtyard")
    (47 "F.CrtYd" user "F.Courtyard")
    (48 "B.Fab" user)
    (49 "F.Fab" user)
  )
	(footprint "antmicro-footprints:R_0402_1005Metric" (layer "F.Cu")
    (at 108.95 99.45)
    (descr "Resistor SMD 0402")
    (tags "resistor SMD 0402")
    (property "Author" "Antmicro")
    (property "License" "Apache-2.0")
    (property "MPN" "CR0402-FX-1022GLF")
    (property "Manufacturer" "Bourns")
    (property "Public" "False")
    (property "Sheetfile" "ethernet.kicad_sch")
    (property "Sheetname" "Ethernet")
    (property "Tolerance" "1%")
    (property "Val" "10k2")
    (property "ki_description" "SMD Chip Resistor")
    (property "ki_keywords" "0402, SMT, RESISTOR, PASSIVE")
    (attr smd)
    (fp_text reference "R10" (at 0.07 1.16) (layer "F.SilkS")
        (effects (font (size 0.7 0.7) (thickness 0.127)))
    )
    (fp_text value "R_10k2_0402" (at 0 1.17) (layer "F.Fab")
        (effects (font (size 1 1) (thickness 0.15)))
    )
    (fp_text user "Author: Antmicro" (at -0.95 4.169) (layer "F.Fab") hide
        (effects (font (size 0.7 0.7) (thickness 0.15)) (justify left bottom))
    )
    (fp_text user "${REFERENCE}" (at 0 0) (layer "F.Fab")
        (effects (font (size 0.25 0.25) (thickness 0.04)))
    )
    (fp_text user "License: Apache-2.0" (at -0.95 5.169) (layer "F.Fab") hide
        (effects (font (size 0.7 0.7) (thickness 0.15)) (justify left bottom))
    )
    (fp_rect (start -0.925 -0.47) (end 0.925 0.47)
      (stroke (width 0.05) (type default)) (fill none) (layer "F.CrtYd"))
    (fp_rect (start -0.5 -0.25) (end 0.5 0.25)
      (stroke (width 0.15) (type solid)) (fill none) (layer "F.Fab"))
    (pad "1" smd roundrect (at -0.48 0) (size 0.59 0.64) (layers "F.Cu" "F.Paste" "F.Mask") (roundrect_rratio 0.25)
      (net 197 "ETH_INT_N") (pintype "passive"))
    (pad "2" smd roundrect (at 0.48 0) (size 0.59 0.64) (layers "F.Cu" "F.Paste" "F.Mask") (roundrect_rratio 0.25)
      (net 2 "VCC3V3") (pintype "passive"))
  )
	(footprint "antmicro-footprints:R_0402_1005Metric" (layer "F.Cu")
    (at 108.95 97.15)
    (descr "Resistor SMD 0402")
    (tags "resistor SMD 0402")
    (property "Author" "Antmicro")
    (property "License" "Apache-2.0")
    (property "MPN" "CR0402-FX-1022GLF")
    (property "Manufacturer" "Bourns")
    (property "Public" "False")
    (property "Sheetfile" "ethernet.kicad_sch")
    (property "Sheetname" "Ethernet")
    (property "Tolerance" "1%")
    (property "Val" "10k2")
    (property "ki_description" "SMD Chip Resistor")
    (property "ki_keywords" "0402, SMT, RESISTOR, PASSIVE")
    (attr smd)
    (fp_text reference "R7" (at 0.04 1.04) (layer "F.SilkS")
        (effects (font (size 0.7 0.7) (thickness 0.127)))
    )
    (fp_text value "R_10k2_0402" (at 0 1.17) (layer "F.Fab")
        (effects (font (size 1 1) (thickness 0.15)))
    )
    (fp_text user "Author: Antmicro" (at -0.95 4.169) (layer "F.Fab") hide
        (effects (font (size 0.7 0.7) (thickness 0.15)) (justify left bottom))
    )
    (fp_text user "${REFERENCE}" (at 0 0) (layer "F.Fab")
        (effects (font (size 0.25 0.25) (thickness 0.04)))
    )
    (fp_text user "License: Apache-2.0" (at -0.95 5.169) (layer "F.Fab") hide
        (effects (font (size 0.7 0.7) (thickness 0.15)) (justify left bottom))
    )
    (fp_rect (start -0.925 -0.47) (end 0.925 0.47)
      (stroke (width 0.05) (type default)) (fill none) (layer "F.CrtYd"))
    (fp_rect (start -0.5 -0.25) (end 0.5 0.25)
      (stroke (width 0.15) (type solid)) (fill none) (layer "F.Fab"))
    (pad "1" smd roundrect (at -0.48 0) (size 0.59 0.64) (layers "F.Cu" "F.Paste" "F.Mask") (roundrect_rratio 0.25)
      (net 160 "RGMII_REF_CLK") (pintype "passive"))
    (pad "2" smd roundrect (at 0.48 0) (size 0.59 0.64) (layers "F.Cu" "F.Paste" "F.Mask") (roundrect_rratio 0.25)
      (net 2 "VCC3V3") (pintype "passive"))
  )
	(footprint "antmicro-footprints:R_0402_1005Metric" (layer "F.Cu")
    (at 106 104 -90)
    (descr "Resistor SMD 0402")
    (tags "resistor SMD 0402")
    (property "Author" "Antmicro")
    (property "License" "Apache-2.0")
    (property "MPN" "CR0402-FX-1022GLF")
    (property "Manufacturer" "Bourns")
    (property "Public" "False")
    (property "Sheetfile" "ethernet.kicad_sch")
    (property "Sheetname" "Ethernet")
    (property "Tolerance" "1%")
    (property "Val" "10k2")
    (property "ki_description" "SMD Chip Resistor")
    (property "ki_keywords" "0402, SMT, RESISTOR, PASSIVE")
    (attr smd)
    (fp_text reference "R6" (at 0.04 -8.93738 90) (layer "F.SilkS")
        (effects (font (size 0.7 0.7) (thickness 0.127)))
    )
    (fp_text value "R_10k2_0402" (at 0 1.17 90) (layer "F.Fab")
        (effects (font (size 1 1) (thickness 0.15)))
    )
    (fp_text user "${REFERENCE}" (at 0 0 90) (layer "F.Fab")
        (effects (font (size 0.25 0.25) (thickness 0.04)))
    )
    (fp_text user "License: Apache-2.0" (at -0.95 5.169 -90) (layer "F.Fab") hide
        (effects (font (size 0.7 0.7) (thickness 0.15)) (justify left bottom))
    )
    (fp_text user "Author: Antmicro" (at -0.95 4.169 -90) (layer "F.Fab") hide
        (effects (font (size 0.7 0.7) (thickness 0.15)) (justify left bottom))
    )
    (fp_rect (start -0.925 -0.47) (end 0.925 0.47)
      (stroke (width 0.05) (type default)) (fill none) (layer "F.CrtYd"))
    (fp_rect (start -0.5 -0.25) (end 0.5 0.25)
      (stroke (width 0.15) (type solid)) (fill none) (layer "F.Fab"))
    (pad "1" smd roundrect (at -0.48 0 270) (size 0.59 0.64) (layers "F.Cu" "F.Paste" "F.Mask") (roundrect_rratio 0.25)
      (net 159 "RGMII_RX_CLK") (pintype "passive"))
    (pad "2" smd roundrect (at 0.48 0 270) (size 0.59 0.64) (layers "F.Cu" "F.Paste" "F.Mask") (roundrect_rratio 0.25)
      (net 2 "VCC3V3") (pintype "passive"))
  )
	(footprint "antmicro-footprints:R_0402_1005Metric" (layer "F.Cu")
    (at 105 104 -90)
    (descr "Resistor SMD 0402")
    (tags "resistor SMD 0402")
    (property "Author" "Antmicro")
    (property "License" "Apache-2.0")
    (property "MPN" "CR0402-FX-1022GLF")
    (property "Manufacturer" "Bourns")
    (property "Public" "False")
    (property "Sheetfile" "ethernet.kicad_sch")
    (property "Sheetname" "Ethernet")
    (property "Tolerance" "1%")
    (property "Val" "10k2")
    (property "ki_description" "SMD Chip Resistor")
    (property "ki_keywords" "0402, SMT, RESISTOR, PASSIVE")
    (attr smd)
    (fp_text reference "R5" (at 0.04 -8.941904 90) (layer "F.SilkS")
        (effects (font (size 0.7 0.7) (thickness 0.127)))
    )
    (fp_text value "R_10k2_0402" (at 0 1.17 90) (layer "F.Fab")
        (effects (font (size 1 1) (thickness 0.15)))
    )
    (fp_text user "Author: Antmicro" (at -0.95 4.169 -90) (layer "F.Fab") hide
        (effects (font (size 0.7 0.7) (thickness 0.15)) (justify left bottom))
    )
    (fp_text user "${REFERENCE}" (at 0 0 90) (layer "F.Fab")
        (effects (font (size 0.25 0.25) (thickness 0.04)))
    )
    (fp_text user "License: Apache-2.0" (at -0.95 5.169 -90) (layer "F.Fab") hide
        (effects (font (size 0.7 0.7) (thickness 0.15)) (justify left bottom))
    )
    (fp_rect (start -0.925 -0.47) (end 0.925 0.47)
      (stroke (width 0.05) (type default)) (fill none) (layer "F.CrtYd"))
    (fp_rect (start -0.5 -0.25) (end 0.5 0.25)
      (stroke (width 0.15) (type solid)) (fill none) (layer "F.Fab"))
    (pad "1" smd roundrect (at -0.48 0 270) (size 0.59 0.64) (layers "F.Cu" "F.Paste" "F.Mask") (roundrect_rratio 0.25)
      (net 158 "RGMII_RX_DV") (pintype "passive"))
    (pad "2" smd roundrect (at 0.48 0 270) (size 0.59 0.64) (layers "F.Cu" "F.Paste" "F.Mask") (roundrect_rratio 0.25)
      (net 2 "VCC3V3") (pintype "passive"))
  )
	(footprint "antmicro-footprints:QFN-48-1EP_7x7x0.9mm_P0.5mm_EP3.5x3.5mm" (layer "F.Cu")
    (at 103.2 96.45 -90)
    (property "Author" "Antmicro")
    (property "License" "Apache-2.0")
    (property "MPN" "KSZ9031RNXCA")
    (property "Manufacturer" "Microchip Technology")
    (property "Sheetfile" "ethernet.kicad_sch")
    (property "Sheetname" "Ethernet")
    (property "ki_description" "Ethernet Controller, 1000 Mbps, IEEE 802.3, 1.14 V, 3.465 V, QFN, 48 Pins")
    (property "ki_keywords" "SMT, TRANSCEIVER, IC, ETHERNET, PHY")
    (attr smd)
    (fp_text reference "U1" (at -4.66 4.66) (layer "F.SilkS")
        (effects (font (size 0.7 0.7) (thickness 0.127)) (justify left))
    )
    (fp_text value "KSZ9031RNXCA" (at 0.0254 5.7404 90) (layer "F.Fab")
        (effects (font (size 1.27 1.27) (thickness 0.15)))
    )
    (fp_text user "Author: Antmicro" (at -4.202 8.4 -90) (layer "F.Fab") hide
        (effects (font (size 0.7 0.7) (thickness 0.15)) (justify left bottom))
    )
    (fp_text user "License: Apache-2.0" (at -4.202 9.598 -90) (layer "F.Fab") hide
        (effects (font (size 0.7 0.7) (thickness 0.15)) (justify left bottom))
    )
    (fp_text user "${REFERENCE}" (at -4.202 7.2 -90) (layer "F.Fab") hide
        (effects (font (size 0.7 0.7) (thickness 0.15)) (justify left bottom))
    )
    (fp_line (start -3.65 -3.3) (end -3.65 -3.65)
      (stroke (width 0.15) (type solid)) (layer "F.SilkS"))
    (fp_line (start -3.65 3.648) (end -3.65 3.249)
      (stroke (width 0.15) (type solid)) (layer "F.SilkS"))
    (fp_line (start -3.3 -3.65) (end -3.65 -3.65)
      (stroke (width 0.15) (type solid)) (layer "F.SilkS"))
    (fp_line (start -3.25 3.648) (end -3.65 3.648)
      (stroke (width 0.15) (type solid)) (layer "F.SilkS"))
    (fp_line (start 3.249 -3.65) (end 3.648 -3.65)
      (stroke (width 0.15) (type solid)) (layer "F.SilkS"))
    (fp_line (start 3.249 3.648) (end 3.648 3.648)
      (stroke (width 0.15) (type solid)) (layer "F.SilkS"))
    (fp_line (start 3.648 -3.65) (end 3.648 -3.25)
      (stroke (width 0.15) (type solid)) (layer "F.SilkS"))
    (fp_line (start 3.648 3.648) (end 3.648 3.249)
      (stroke (width 0.15) (type solid)) (layer "F.SilkS"))
    (fp_circle (center -3.7 -3.05) (end -3.65 -3.05)
      (stroke (width 0.15) (type solid)) (fill solid) (layer "F.SilkS"))
    (fp_rect (start -4.15 -4.15) (end 4.15 4.15)
      (stroke (width 0.05) (type solid)) (fill none) (layer "F.CrtYd"))
    (fp_line (start -3.5 -2.5) (end -3.5 3.499)
      (stroke (width 0.15) (type solid)) (layer "F.Fab"))
    (fp_line (start -3.5 3.499) (end 3.499 3.499)
      (stroke (width 0.15) (type solid)) (layer "F.Fab"))
    (fp_line (start -2.5 -3.5) (end -3.5 -2.5)
      (stroke (width 0.15) (type solid)) (layer "F.Fab"))
    (fp_line (start 3.499 -3.5) (end -2.5 -3.5)
      (stroke (width 0.15) (type solid)) (layer "F.Fab"))
    (fp_line (start 3.499 3.499) (end 3.499 -3.5)
      (stroke (width 0.15) (type solid)) (layer "F.Fab"))
    (pad "1" smd oval (at -3.5 -2.75) (size 0.3 0.9) (layers "F.Cu" "F.Paste" "F.Mask")
      (net 4 "/Ethernet/AVDDH") (pinfunction "AVDDH") (pintype "power_in"))
    (pad "2" smd oval (at -3.5 -2.25) (size 0.3 0.9) (layers "F.Cu" "F.Paste" "F.Mask")
      (net 148 "/Ethernet/ETH1_P") (pinfunction "TXRXP_A") (pintype "bidirectional"))
    (pad "3" smd oval (at -3.5 -1.75) (size 0.3 0.9) (layers "F.Cu" "F.Paste" "F.Mask")
      (net 151 "/Ethernet/ETH1_N") (pinfunction "TXRXM_A") (pintype "bidirectional"))
    (pad "4" smd oval (at -3.5 -1.25) (size 0.3 0.9) (layers "F.Cu" "F.Paste" "F.Mask")
      (net 9 "/Ethernet/AVDDL") (pinfunction "AVDDL") (pintype "power_in"))
    (pad "5" smd oval (at -3.5 -0.75) (size 0.3 0.9) (layers "F.Cu" "F.Paste" "F.Mask")
      (net 147 "/Ethernet/ETH2_P") (pinfunction "TXRXP_B") (pintype "bidirectional"))
    (pad "6" smd oval (at -3.5 -0.25) (size 0.3 0.9) (layers "F.Cu" "F.Paste" "F.Mask")
      (net 150 "/Ethernet/ETH2_N") (pinfunction "TXRXM_B") (pintype "bidirectional"))
    (pad "7" smd oval (at -3.5 0.248) (size 0.3 0.9) (layers "F.Cu" "F.Paste" "F.Mask")
      (net 146 "/Ethernet/ETH3_P") (pinfunction "TXRXP_C") (pintype "bidirectional"))
    (pad "8" smd oval (at -3.5 0.748) (size 0.3 0.9) (layers "F.Cu" "F.Paste" "F.Mask")
      (net 152 "/Ethernet/ETH3_N") (pinfunction "TXRXM_C") (pintype "bidirectional"))
    (pad "9" smd oval (at -3.5 1.249) (size 0.3 0.9) (layers "F.Cu" "F.Paste" "F.Mask")
      (net 9 "/Ethernet/AVDDL") (pinfunction "AVDDL") (pintype "passive"))
    (pad "10" smd oval (at -3.5 1.749) (size 0.3 0.9) (layers "F.Cu" "F.Paste" "F.Mask")
      (net 149 "/Ethernet/ETH4_P") (pinfunction "TXRXP_D") (pintype "bidirectional"))
    (pad "11" smd oval (at -3.5 2.249) (size 0.3 0.9) (layers "F.Cu" "F.Paste" "F.Mask")
      (net 153 "/Ethernet/ETH4_N") (pinfunction "TXRXM_D") (pintype "bidirectional"))
    (pad "12" smd oval (at -3.5 2.749) (size 0.3 0.9) (layers "F.Cu" "F.Paste" "F.Mask")
      (net 4 "/Ethernet/AVDDH") (pinfunction "AVDDH") (pintype "passive"))
    (pad "13" smd oval (at -2.75 3.499 270) (size 0.3 0.9) (layers "F.Cu" "F.Paste" "F.Mask")
      (net 438 "unconnected-(U1-NC-Pad13)") (pinfunction "NC") (pintype "no_connect"))
    (pad "14" smd oval (at -2.25 3.499 270) (size 0.3 0.9) (layers "F.Cu" "F.Paste" "F.Mask")
      (net 211 "VCC1V2") (pinfunction "DVDDL") (pintype "power_in"))
    (pad "15" smd oval (at -1.75 3.499 270) (size 0.3 0.9) (layers "F.Cu" "F.Paste" "F.Mask")
      (net 165 "/Ethernet/ETH_LED2") (pinfunction "LED2/PHYAD1") (pintype "bidirectional"))
    (pad "16" smd oval (at -1.25 3.499 270) (size 0.3 0.9) (layers "F.Cu" "F.Paste" "F.Mask")
      (net 2 "VCC3V3") (pinfunction "DVDDH") (pintype "power_in"))
    (pad "17" smd oval (at -0.75 3.499 270) (size 0.3 0.9) (layers "F.Cu" "F.Paste" "F.Mask")
      (net 164 "/Ethernet/ETH_LED1") (pinfunction "LED1/PHAD0/PME_N1") (pintype "bidirectional"))
    (pad "18" smd oval (at -0.25 3.499 270) (size 0.3 0.9) (layers "F.Cu" "F.Paste" "F.Mask")
      (net 211 "VCC1V2") (pinfunction "DVDDL") (pintype "passive"))
    (pad "19" smd oval (at 0.248 3.499 270) (size 0.3 0.9) (layers "F.Cu" "F.Paste" "F.Mask")
      (net 202 "RGMII_TXD0") (pinfunction "TXD0") (pintype "input"))
    (pad "20" smd oval (at 0.748 3.499 270) (size 0.3 0.9) (layers "F.Cu" "F.Paste" "F.Mask")
      (net 198 "RGMII_TXD1") (pinfunction "TXD1") (pintype "input"))
    (pad "21" smd oval (at 1.249 3.499 270) (size 0.3 0.9) (layers "F.Cu" "F.Paste" "F.Mask")
      (net 199 "RGMII_TXD2") (pinfunction "TXD2") (pintype "input"))
    (pad "22" smd oval (at 1.749 3.499 270) (size 0.3 0.9) (layers "F.Cu" "F.Paste" "F.Mask")
      (net 201 "RGMII_TXD3") (pinfunction "TXD3") (pintype "input"))
    (pad "23" smd oval (at 2.249 3.499 270) (size 0.3 0.9) (layers "F.Cu" "F.Paste" "F.Mask")
      (net 211 "VCC1V2") (pinfunction "DVDDL") (pintype "passive"))
    (pad "24" smd oval (at 2.749 3.499 270) (size 0.3 0.9) (layers "F.Cu" "F.Paste" "F.Mask")
      (net 200 "RGMII_TX_CLK") (pinfunction "GTX_CLK") (pintype "input"))
    (pad "25" smd oval (at 3.499 2.749) (size 0.3 0.9) (layers "F.Cu" "F.Paste" "F.Mask")
      (net 296 "RGMII_TX_EN") (pinfunction "TX_EN") (pintype "input"))
    (pad "26" smd oval (at 3.499 2.249) (size 0.3 0.9) (layers "F.Cu" "F.Paste" "F.Mask")
      (net 211 "VCC1V2") (pinfunction "DVDDL") (pintype "passive"))
    (pad "27" smd oval (at 3.499 1.749) (size 0.3 0.9) (layers "F.Cu" "F.Paste" "F.Mask")
      (net 157 "RGMII_RXD3") (pinfunction "RXD3/MODE3") (pintype "input"))
    (pad "28" smd oval (at 3.499 1.249) (size 0.3 0.9) (layers "F.Cu" "F.Paste" "F.Mask")
      (net 156 "RGMII_RXD2") (pinfunction "RXD2/MODE2") (pintype "input"))
    (pad "29" smd oval (at 3.499 0.748) (size 0.3 0.9) (layers "F.Cu" "F.Paste" "F.Mask")
      (net 1 "GND") (pinfunction "VSS") (pintype "power_in"))
    (pad "30" smd oval (at 3.499 0.248) (size 0.3 0.9) (layers "F.Cu" "F.Paste" "F.Mask")
      (net 211 "VCC1V2") (pinfunction "DVDDL") (pintype "passive"))
    (pad "31" smd oval (at 3.499 -0.25) (size 0.3 0.9) (layers "F.Cu" "F.Paste" "F.Mask")
      (net 155 "RGMII_RXD1") (pinfunction "RXD1/MODE1") (pintype "input"))
    (pad "32" smd oval (at 3.499 -0.75) (size 0.3 0.9) (layers "F.Cu" "F.Paste" "F.Mask")
      (net 154 "RGMII_RXD0") (pinfunction "RXD0/MODE0") (pintype "input"))
    (pad "33" smd oval (at 3.499 -1.25) (size 0.3 0.9) (layers "F.Cu" "F.Paste" "F.Mask")
      (net 158 "RGMII_RX_DV") (pinfunction "RX_DV/CLK125_EN") (pintype "input"))
    (pad "34" smd oval (at 3.499 -1.75) (size 0.3 0.9) (layers "F.Cu" "F.Paste" "F.Mask")
      (net 2 "VCC3V3") (pinfunction "DVDDH") (pintype "passive"))
    (pad "35" smd oval (at 3.499 -2.25) (size 0.3 0.9) (layers "F.Cu" "F.Paste" "F.Mask")
      (net 159 "RGMII_RX_CLK") (pinfunction "RX_CLK/PHYAD2") (pintype "input"))
    (pad "36" smd oval (at 3.499 -2.75) (size 0.3 0.9) (layers "F.Cu" "F.Paste" "F.Mask")
      (net 161 "ETH_MDC") (pinfunction "MDC") (pintype "input"))
    (pad "37" smd oval (at 2.749 -3.5 270) (size 0.3 0.9) (layers "F.Cu" "F.Paste" "F.Mask")
      (net 162 "ETH_MDIO") (pinfunction "MDIO") (pintype "input"))
    (pad "38" smd oval (at 2.249 -3.5 270) (size 0.3 0.9) (layers "F.Cu" "F.Paste" "F.Mask")
      (net 197 "ETH_INT_N") (pinfunction "~{INT/PME}") (pintype "input"))
    (pad "39" smd oval (at 1.749 -3.5 270) (size 0.3 0.9) (layers "F.Cu" "F.Paste" "F.Mask")
      (net 211 "VCC1V2") (pinfunction "DVDDL") (pintype "passive"))
    (pad "40" smd oval (at 1.249 -3.5 270) (size 0.3 0.9) (layers "F.Cu" "F.Paste" "F.Mask")
      (net 2 "VCC3V3") (pinfunction "DVDDH") (pintype "passive"))
    (pad "41" smd oval (at 0.748 -3.5 270) (size 0.3 0.9) (layers "F.Cu" "F.Paste" "F.Mask")
      (net 160 "RGMII_REF_CLK") (pinfunction "CLK125_NDO/LED_MODE") (pintype "input"))
    (pad "42" smd oval (at 0.248 -3.5 270) (size 0.3 0.9) (layers "F.Cu" "F.Paste" "F.Mask")
      (net 163 "ETH_~{RESET}") (pinfunction "~{RESET}") (pintype "input"))
    (pad "43" smd oval (at -0.25 -3.5 270) (size 0.3 0.9) (layers "F.Cu" "F.Paste" "F.Mask")
      (net 439 "unconnected-(U1-LDO_O-Pad43)") (pinfunction "LDO_O") (pintype "input+no_connect"))
    (pad "44" smd oval (at -0.75 -3.5 270) (size 0.3 0.9) (layers "F.Cu" "F.Paste" "F.Mask")
      (net 10 "/Ethernet/AVDDL_PLL") (pinfunction "AVDDL_PLL") (pintype "power_in"))
    (pad "45" smd oval (at -1.25 -3.5 270) (size 0.3 0.9) (layers "F.Cu" "F.Paste" "F.Mask")
      (net 440 "unconnected-(U1-XO-Pad45)") (pinfunction "XO") (pintype "input+no_connect"))
    (pad "46" smd oval (at -1.75 -3.5 270) (size 0.3 0.9) (layers "F.Cu" "F.Paste" "F.Mask")
      (net 676 "/Ethernet/PHY_CLK") (pinfunction "XI") (pintype "input"))
    (pad "47" smd oval (at -2.25 -3.5 270) (size 0.3 0.9) (layers "F.Cu" "F.Paste" "F.Mask")
      (net 441 "unconnected-(U1-NC-Pad47)") (pinfunction "NC") (pintype "no_connect"))
    (pad "48" smd oval (at -2.75 -3.5 270) (size 0.3 0.9) (layers "F.Cu" "F.Paste" "F.Mask")
      (net 402 "Net-(U1-ISET)") (pinfunction "ISET") (pintype "output"))
    (pad "49" smd rect (at 0 0 270) (size 3.5 3.5) (layers "F.Cu" "F.Paste" "F.Mask")
      (net 1 "GND") (pinfunction "PAD_GND") (pintype "power_in"))
  )
)
